# T6G (Grand Teton) — schematic netlist excerpt (pin names and nets, part order shuffled) for the footprints in the layout excerpt that follows; sources: Cadence DE-HDL packaged netlist, KiCad conversion of 04192023_DAF0TMB3IC0_F0TG_MB_C_brd_V02_OCP.brd

R501  Q_RES  15 1% CHIP  pkg 0402LF  page 38 : A = M_B_CPU1_ALERT_N ; B = M_B_CPU1_ALERT_R_N
C980  Q_CAP  1UF 4V 20% X6S  pkg 0201  page 301 : A = P0V9_CPU0_RT_2D ; B = GND
R6004  Q_RES  0 5% CHIP  pkg 0402LF  page 150 : A = I3C_SCM_2_SCL ; B = I3C_SCM_2_R_SCL

(kicad_pcb
	(version 20260206)
	(generator "pcbnew")
	(generator_version "10.0")
	(general
		(thickness 1.6)
		(legacy_teardrops no)
	)
	(paper "A4")
	(title_block
		(title "04192023_DAF0TMB3IC0_F0TG_MB_C_brd_V02_OCP.brd")
		(comment 1 "Grand Teton / footprints 7732-7734 of 8354")
	)
	(layers
		(0 "F.Cu" signal "TOP")
		(4 "In1.Cu" signal "GND")
		(6 "In2.Cu" signal "IN1")
		(8 "In3.Cu" signal "GND1")
		(10 "In4.Cu" signal "IN2")
		(12 "In5.Cu" signal "GND2")
		(14 "In6.Cu" signal "IN3")
		(16 "In7.Cu" signal "GND3")
		(18 "In8.Cu" signal "VCC")
		(20 "In9.Cu" signal "VCC1")
		(22 "In10.Cu" signal "GND4")
		(24 "In11.Cu" signal "IN4")
		(26 "In12.Cu" signal "GND5")
		(28 "In13.Cu" signal "IN5")
		(30 "In14.Cu" signal "GND6")
		(32 "In15.Cu" signal "IN6")
		(34 "In16.Cu" signal "GND7")
		(2 "B.Cu" signal "BOTTOM")
		(9 "F.Adhes" user "F.Adhesive")
		(11 "B.Adhes" user "B.Adhesive")
		(13 "F.Paste" user "Package Geometry/Pastemask Top")
		(15 "B.Paste" user "Package Geometry/Pastemask Bottom")
		(5 "F.SilkS" user "Ref Des/Silkscreen Top")
		(7 "B.SilkS" user "Ref Des/Silkscreen Bottom")
		(1 "F.Mask" user "Board Geometry/Soldermask Top")
		(3 "B.Mask" user "Board Geometry/Soldermask Bottom")
		(17 "Dwgs.User" user "User.Drawings")
		(19 "Cmts.User" user "User.Comments")
		(21 "Eco1.User" user "User.Eco1")
		(23 "Eco2.User" user "User.Eco2")
		(25 "Edge.Cuts" user "Board Geometry/Outline")
		(27 "Margin" user)
		(31 "F.CrtYd" user "Package Geometry/Place Bound Top")
		(29 "B.CrtYd" user "Package Geometry/Place Bound Bottom")
		(35 "F.Fab" user "Ref Des/Assembly Top")
		(33 "B.Fab" user "Ref Des/Assembly Bottom")
	)
	(footprint ""
		(layer "B.Cu")
		(at 186.345322 -13.60043 -90)
		(property "Reference" "R6004"
			(at 0 0 90)
			(layer "B.SilkS")
			(hide yes)
			(effects
				(font
					(size 1.27 1.27)
				)
				(justify mirror)
			)
		)
		(property "Value" ""
			(at 0 0 90)
			(layer "B.Fab")
			(effects
				(font
					(size 1.27 1.27)
				)
				(justify mirror)
			)
		)
		(duplicate_pad_numbers_are_jumpers no)
		(fp_line
			(start -0.7874 0.4064)
			(end 0.7874 0.4064)
			(stroke
				(width 0.1524)
				(type default)
			)
			(layer "B.SilkS")
		)
		(fp_line
			(start 0.7874 0.4064)
			(end 0.7874 -0.4064)
			(stroke
				(width 0.1524)
				(type default)
			)
			(layer "B.SilkS")
		)
		(fp_line
			(start -0.7874 -0.4064)
			(end -0.7874 0.4064)
			(stroke
				(width 0.1524)
				(type default)
			)
			(layer "B.SilkS")
		)
		(fp_line
			(start 0.7874 -0.4064)
			(end -0.7874 -0.4064)
			(stroke
				(width 0.1524)
				(type default)
			)
			(layer "B.SilkS")
		)
		(fp_line
			(start -0.67945 0.3048)
			(end -0.120396 0.3048)
			(stroke
				(width 0.1)
				(type default)
			)
			(layer "B.Fab")
		)
		(fp_line
			(start -0.120396 0.3048)
			(end -0.120396 0.2794)
			(stroke
				(width 0.1)
				(type default)
			)
			(layer "B.Fab")
		)
		(fp_line
			(start 0.12065 0.3048)
			(end 0.67945 0.3048)
			(stroke
				(width 0.1)
				(type default)
			)
			(layer "B.Fab")
		)
		(fp_line
			(start 0.67945 0.3048)
			(end 0.67945 -0.305054)
			(stroke
				(width 0.1)
				(type default)
			)
			(layer "B.Fab")
		)
		(fp_line
			(start -0.120396 0.2794)
			(end 0.12065 0.2794)
			(stroke
				(width 0.1)
				(type default)
			)
			(layer "B.Fab")
		)
		(fp_line
			(start 0.12065 0.2794)
			(end 0.12065 0.3048)
			(stroke
				(width 0.1)
				(type default)
			)
			(layer "B.Fab")
		)
		(fp_line
			(start -0.12065 -0.2794)
			(end -0.12065 -0.3048)
			(stroke
				(width 0.1)
				(type default)
			)
			(layer "B.Fab")
		)
		(fp_line
			(start 0.12065 -0.2794)
			(end -0.12065 -0.2794)
			(stroke
				(width 0.1)
				(type default)
			)
			(layer "B.Fab")
		)
		(fp_line
			(start -0.67945 -0.3048)
			(end -0.67945 0.3048)
			(stroke
				(width 0.1)
				(type default)
			)
			(layer "B.Fab")
		)
		(fp_line
			(start -0.12065 -0.3048)
			(end -0.67945 -0.3048)
			(stroke
				(width 0.1)
				(type default)
			)
			(layer "B.Fab")
		)
		(fp_line
			(start 0.12065 -0.305054)
			(end 0.12065 -0.2794)
			(stroke
				(width 0.1)
				(type default)
			)
			(layer "B.Fab")
		)
		(fp_line
			(start 0.67945 -0.305054)
			(end 0.12065 -0.305054)
			(stroke
				(width 0.1)
				(type default)
			)
			(layer "B.Fab")
		)
		(pad "1" smd circle
			(at 0.40005 0 90)
			(size 0 0)
			(layers "B.Cu" "B.Mask" "B.Paste")
			(net "I3C_SCM_2_SCL")
		)
		(pad "2" smd circle
			(at -0.40005 0 90)
			(size 0 0)
			(layers "B.Cu" "B.Mask" "B.Paste")
			(net "I3C_SCM_2_R_SCL")
		)
	)
	(footprint ""
		(layer "B.Cu")
		(at 415.018982 -399.291302 90)
		(property "Reference" "C980"
			(at 0 0 90)
			(layer "B.SilkS")
			(hide yes)
			(effects
				(font
					(size 1.27 1.27)
				)
				(justify mirror)
			)
		)
		(property "Value" ""
			(at 0 0 90)
			(layer "B.Fab")
			(effects
				(font
					(size 1.27 1.27)
				)
				(justify mirror)
			)
		)
		(duplicate_pad_numbers_are_jumpers no)
		(fp_line
			(start 0.299974 -0.150114)
			(end -0.299974 -0.150114)
			(stroke
				(width 0.1)
				(type default)
			)
			(layer "B.Fab")
		)
		(fp_line
			(start -0.299974 -0.150114)
			(end -0.299974 0.150114)
			(stroke
				(width 0.1)
				(type default)
			)
			(layer "B.Fab")
		)
		(fp_line
			(start 0.299974 0.150114)
			(end 0.299974 -0.150114)
			(stroke
				(width 0.1)
				(type default)
			)
			(layer "B.Fab")
		)
		(fp_line
			(start -0.299974 0.150114)
			(end 0.299974 0.150114)
			(stroke
				(width 0.1)
				(type default)
			)
			(layer "B.Fab")
		)
		(pad "1" smd rect
			(at 0.2667 0 270)
			(size 0.3048 0.381)
			(layers "B.Cu" "B.Mask" "B.Paste")
			(net "P0V9_CPU0_RT_2D")
		)
		(pad "2" smd rect
			(at -0.2667 0 270)
			(size 0.3048 0.381)
			(layers "B.Cu" "B.Mask" "B.Paste")
			(net "GND")
		)
	)
	(footprint ""
		(layer "B.Cu")
		(at 52.881022 -244.085364 180)
		(property "Reference" "R501"
			(at 0 0 0)
			(layer "B.SilkS")
			(hide yes)
			(effects
				(font
					(size 1.27 1.27)
				)
				(justify mirror)
			)
		)
		(property "Value" ""
			(at 0 0 0)
			(layer "B.Fab")
			(effects
				(font
					(size 1.27 1.27)
				)
				(justify mirror)
			)
		)
		(duplicate_pad_numbers_are_jumpers no)
		(fp_line
			(start 0.7874 0.4064)
			(end 0.7874 -0.4064)
			(stroke
				(width 0.1524)
				(type default)
			)
			(layer "B.SilkS")
		)
		(fp_line
			(start 0.7874 -0.4064)
			(end -0.7874 -0.4064)
			(stroke
				(width 0.1524)
				(type default)
			)
			(layer "B.SilkS")
		)
		(fp_line
			(start -0.7874 0.4064)
			(end 0.7874 0.4064)
			(stroke
				(width 0.1524)
				(type default)
			)
			(layer "B.SilkS")
		)
		(fp_line
			(start -0.7874 -0.4064)
			(end -0.7874 0.4064)
			(stroke
				(width 0.1524)
				(type default)
			)
			(layer "B.SilkS")
		)
		(fp_line
			(start 0.67945 0.3048)
			(end 0.67945 -0.305054)
			(stroke
				(width 0.1)
				(type default)
			)
			(layer "B.Fab")
		)
		(fp_line
			(start 0.67945 -0.305054)
			(end 0.12065 -0.305054)
			(stroke
				(width 0.1)
				(type default)
			)
			(layer "B.Fab")
		)
		(fp_line
			(start 0.12065 0.3048)
			(end 0.67945 0.3048)
			(stroke
				(width 0.1)
				(type default)
			)
			(layer "B.Fab")
		)
		(fp_line
			(start 0.12065 0.2794)
			(end 0.12065 0.3048)
			(stroke
				(width 0.1)
				(type default)
			)
			(layer "B.Fab")
		)
		(fp_line
			(start 0.12065 -0.2794)
			(end -0.12065 -0.2794)
			(stroke
				(width 0.1)
				(type default)
			)
			(layer "B.Fab")
		)
		(fp_line
			(start 0.12065 -0.305054)
			(end 0.12065 -0.2794)
			(stroke
				(width 0.1)
				(type default)
			)
			(layer "B.Fab")
		)
		(fp_line
			(start -0.120396 0.3048)
			(end -0.120396 0.2794)
			(stroke
				(width 0.1)
				(type default)
			)
			(layer "B.Fab")
		)
		(fp_line
			(start -0.120396 0.2794)
			(end 0.12065 0.2794)
			(stroke
				(width 0.1)
				(type default)
			)
			(layer "B.Fab")
		)
		(fp_line
			(start -0.12065 -0.2794)
			(end -0.12065 -0.3048)
			(stroke
				(width 0.1)
				(type default)
			)
			(layer "B.Fab")
		)
		(fp_line
			(start -0.12065 -0.3048)
			(end -0.67945 -0.3048)
			(stroke
				(width 0.1)
				(type default)
			)
			(layer "B.Fab")
		)
		(fp_line
			(start -0.67945 0.3048)
			(end -0.120396 0.3048)
			(stroke
				(width 0.1)
				(type default)
			)
			(layer "B.Fab")
		)
		(fp_line
			(start -0.67945 -0.3048)
			(end -0.67945 0.3048)
			(stroke
				(width 0.1)
				(type default)
			)
			(layer "B.Fab")
		)
		(pad "1" smd circle
			(at 0.40005 0)
			(size 0 0)
			(layers "B.Cu" "B.Mask" "B.Paste")
			(net "M_B_CPU1_ALERT_N")
		)
		(pad "2" smd circle
			(at -0.40005 0)
			(size 0 0)
			(layers "B.Cu" "B.Mask" "B.Paste")
			(net "M_B_CPU1_ALERT_R_N")
		)
	)
)
